(kicad_pcb
	(version 20260206)
	(generator "pcbnew")
	(generator_version "10.0")
	(general
		(thickness 1.6)
		(legacy_teardrops no)
	)
	(paper "A4")
	(title_block
		(title "Bryce Canyon_F.DPB_16315-1-OCP.brd")
		(comment 1 "Bryce Canyon / footprints 1060-1066 of 2223")
	)
	(layers
		(0 "F.Cu" signal "TOP")
		(4 "In1.Cu" signal "L2GND")
		(6 "In2.Cu" signal "L3")
		(8 "In3.Cu" signal "L4GND")
		(10 "In4.Cu" signal "L5")
		(12 "In5.Cu" signal "L6VCC")
		(14 "In6.Cu" signal "L7VCC")
		(16 "In7.Cu" signal "L8")
		(18 "In8.Cu" signal "L9GND")
		(20 "In9.Cu" signal "L10")
		(22 "In10.Cu" signal "L11GND")
		(2 "B.Cu" signal "BOTTOM")
		(9 "F.Adhes" user "F.Adhesive")
		(11 "B.Adhes" user "B.Adhesive")
		(13 "F.Paste" user "Package Geometry/Pastemask Top")
		(15 "B.Paste" user "Package Geometry/Pastemask Bottom")
		(5 "F.SilkS" user "Ref Des/Silkscreen Top")
		(7 "B.SilkS" user "Ref Des/Silkscreen Bottom")
		(1 "F.Mask" user "Board Geometry/Soldermask Top")
		(3 "B.Mask" user "Board Geometry/Soldermask Bottom")
		(17 "Dwgs.User" user "User.Drawings")
		(19 "Cmts.User" user "User.Comments")
		(21 "Eco1.User" user "User.Eco1")
		(23 "Eco2.User" user "User.Eco2")
		(25 "Edge.Cuts" user "Board Geometry/Outline")
		(27 "Margin" user)
		(31 "F.CrtYd" user "Package Geometry/Place Bound Top")
		(29 "B.CrtYd" user "Package Geometry/Place Bound Bottom")
		(35 "F.Fab" user "Ref Des/Assembly Top")
		(33 "B.Fab" user "Ref Des/Assembly Bottom")
	)
	(footprint ""
		(layer "F.Cu")
		(at 52.202588 -148.6535 -90)
		(property "Reference" "R1229"
			(at 0 0 270)
			(layer "F.SilkS")
			(hide yes)
			(effects
				(font
					(size 1.27 1.27)
				)
			)
		)
		(property "Value" "10KR2F-2-GP"
			(at 0.064008 -3.993896 270)
			(unlocked yes)
			(layer "F.Fab")
			(hide yes)
			(effects
				(font
					(size 1.016 1.016)
					(thickness 0.1524)
				)
			)
		)
		(property "Device Type" "R402H16"
			(at 0.064008 -5.517896 270)
			(unlocked yes)
			(layer "F.Fab")
			(hide yes)
			(effects
				(font
					(size 1.016 1.016)
					(thickness 0.1524)
				)
			)
		)
		(duplicate_pad_numbers_are_jumpers no)
		(fp_line
			(start -0.508 -0.9398)
			(end -0.508 0.9398)
			(stroke
				(width 0.1524)
				(type default)
			)
			(layer "F.SilkS")
		)
		(fp_line
			(start 0.508 -0.9398)
			(end -0.508 -0.9398)
			(stroke
				(width 0.1524)
				(type default)
			)
			(layer "F.SilkS")
		)
		(fp_rect
			(start -0.508 0.9398)
			(end 0.508 -0.9398)
			(stroke
				(width 0)
				(type default)
			)
			(fill no)
			(layer "F.CrtYd")
		)
		(fp_rect
			(start -0.508 0.9398)
			(end 0.508 -0.9398)
			(stroke
				(width 0)
				(type default)
			)
			(fill no)
			(layer "F.Fab")
		)
		(pad "1" smd custom
			(at 0 -0.4445 270)
			(size 0.1397 0.1397)
			(layers "F.Cu" "F.Mask" "F.Paste")
			(net "P5V_A_2")
			(options
				(clearance outline)
				(anchor circle)
			)
			(primitives
				(gr_poly
					(pts
						(arc
							(start -0.1778 -0.2794)
							(mid -0.249642 -0.249642)
							(end -0.2794 -0.1778)
						)
						(arc
							(start -0.2794 0.1778)
							(mid -0.249642 0.249642)
							(end -0.1778 0.2794)
						)
						(arc
							(start 0.1778 0.2794)
							(mid 0.249642 0.249642)
							(end 0.2794 0.1778)
						)
						(arc
							(start 0.2794 -0.1778)
							(mid 0.249642 -0.249642)
							(end 0.1778 -0.2794)
						)
					)
					(width 0)
					(fill yes)
				)
			)
		)
		(pad "2" smd custom
			(at 0 0.4445 270)
			(size 0.1397 0.1397)
			(layers "F.Cu" "F.Mask" "F.Paste")
			(net "P5V_A_2_PGOOD")
			(options
				(clearance outline)
				(anchor circle)
			)
			(primitives
				(gr_poly
					(pts
						(arc
							(start -0.1778 -0.2794)
							(mid -0.249642 -0.249642)
							(end -0.2794 -0.1778)
						)
						(arc
							(start -0.2794 0.1778)
							(mid -0.249642 0.249642)
							(end -0.1778 0.2794)
						)
						(arc
							(start 0.1778 0.2794)
							(mid 0.249642 0.249642)
							(end 0.2794 0.1778)
						)
						(arc
							(start 0.2794 -0.1778)
							(mid 0.249642 -0.249642)
							(end 0.1778 -0.2794)
						)
					)
					(width 0)
					(fill yes)
				)
			)
		)
	)
	(footprint ""
		(layer "F.Cu")
		(at 263.398 -272.288)
		(property "Reference" "R103"
			(at 0 0 0)
			(layer "F.SilkS")
			(hide yes)
			(effects
				(font
					(size 1.27 1.27)
				)
			)
		)
		(property "Value" "4K7R2F-GP"
			(at 0.064008 -3.993896 0)
			(unlocked yes)
			(layer "F.Fab")
			(hide yes)
			(effects
				(font
					(size 1.016 1.016)
					(thickness 0.1524)
				)
			)
		)
		(property "Device Type" "R402H16"
			(at 0.064008 -5.517896 0)
			(unlocked yes)
			(layer "F.Fab")
			(hide yes)
			(effects
				(font
					(size 1.016 1.016)
					(thickness 0.1524)
				)
			)
		)
		(duplicate_pad_numbers_are_jumpers no)
		(fp_line
			(start -0.508 -0.9398)
			(end -0.508 0.9398)
			(stroke
				(width 0.1524)
				(type default)
			)
			(layer "F.SilkS")
		)
		(fp_line
			(start 0.508 -0.9398)
			(end -0.508 -0.9398)
			(stroke
				(width 0.1524)
				(type default)
			)
			(layer "F.SilkS")
		)
		(fp_rect
			(start -0.508 0.9398)
			(end 0.508 -0.9398)
			(stroke
				(width 0)
				(type default)
			)
			(fill no)
			(layer "F.CrtYd")
		)
		(fp_rect
			(start -0.508 0.9398)
			(end 0.508 -0.9398)
			(stroke
				(width 0)
				(type default)
			)
			(fill no)
			(layer "F.Fab")
		)
		(pad "1" smd custom
			(at 0 -0.4445)
			(size 0.1397 0.1397)
			(layers "F.Cu" "F.Mask" "F.Paste")
			(net "IO_EXP0_HDD_FAULT_A2")
			(options
				(clearance outline)
				(anchor circle)
			)
			(primitives
				(gr_poly
					(pts
						(arc
							(start -0.1778 -0.2794)
							(mid -0.249642 -0.249642)
							(end -0.2794 -0.1778)
						)
						(arc
							(start -0.2794 0.1778)
							(mid -0.249642 0.249642)
							(end -0.1778 0.2794)
						)
						(arc
							(start 0.1778 0.2794)
							(mid 0.249642 0.249642)
							(end 0.2794 0.1778)
						)
						(arc
							(start 0.2794 -0.1778)
							(mid 0.249642 -0.249642)
							(end 0.1778 -0.2794)
						)
					)
					(width 0)
					(fill yes)
				)
			)
		)
		(pad "2" smd custom
			(at 0 0.4445)
			(size 0.1397 0.1397)
			(layers "F.Cu" "F.Mask" "F.Paste")
			(net "GND")
			(options
				(clearance outline)
				(anchor circle)
			)
			(primitives
				(gr_poly
					(pts
						(arc
							(start -0.1778 -0.2794)
							(mid -0.249642 -0.249642)
							(end -0.2794 -0.1778)
						)
						(arc
							(start -0.2794 0.1778)
							(mid -0.249642 0.249642)
							(end -0.1778 0.2794)
						)
						(arc
							(start 0.1778 0.2794)
							(mid 0.249642 0.249642)
							(end 0.2794 0.1778)
						)
						(arc
							(start 0.2794 -0.1778)
							(mid 0.249642 -0.249642)
							(end 0.1778 -0.2794)
						)
					)
					(width 0)
					(fill yes)
				)
			)
		)
	)
	(footprint ""
		(layer "F.Cu")
		(at 275.17217 -284.734762 180)
		(property "Reference" "R438"
			(at 0 0 180)
			(layer "F.SilkS")
			(hide yes)
			(effects
				(font
					(size 1.27 1.27)
				)
			)
		)
		(property "Value" "1KR2F-3-GP"
			(at 0.064008 -3.993896 180)
			(unlocked yes)
			(layer "F.Fab")
			(hide yes)
			(effects
				(font
					(size 1.016 1.016)
					(thickness 0.1524)
				)
			)
		)
		(property "Device Type" "R402H16"
			(at 0.064008 -5.517896 180)
			(unlocked yes)
			(layer "F.Fab")
			(hide yes)
			(effects
				(font
					(size 1.016 1.016)
					(thickness 0.1524)
				)
			)
		)
		(duplicate_pad_numbers_are_jumpers no)
		(fp_line
			(start 0.508 -0.9398)
			(end -0.508 -0.9398)
			(stroke
				(width 0.1524)
				(type default)
			)
			(layer "F.SilkS")
		)
		(fp_line
			(start -0.508 -0.9398)
			(end -0.508 0.9398)
			(stroke
				(width 0.1524)
				(type default)
			)
			(layer "F.SilkS")
		)
		(fp_rect
			(start -0.508 0.9398)
			(end 0.508 -0.9398)
			(stroke
				(width 0)
				(type default)
			)
			(fill no)
			(layer "F.CrtYd")
		)
		(fp_rect
			(start -0.508 0.9398)
			(end 0.508 -0.9398)
			(stroke
				(width 0)
				(type default)
			)
			(fill no)
			(layer "F.Fab")
		)
		(pad "1" smd custom
			(at 0 -0.4445 180)
			(size 0.1397 0.1397)
			(layers "F.Cu" "F.Mask" "F.Paste")
			(net "P3V3_STBY_A")
			(options
				(clearance outline)
				(anchor circle)
			)
			(primitives
				(gr_poly
					(pts
						(arc
							(start -0.1778 -0.2794)
							(mid -0.249642 -0.249642)
							(end -0.2794 -0.1778)
						)
						(arc
							(start -0.2794 0.1778)
							(mid -0.249642 0.249642)
							(end -0.1778 0.2794)
						)
						(arc
							(start 0.1778 0.2794)
							(mid 0.249642 0.249642)
							(end 0.2794 0.1778)
						)
						(arc
							(start 0.2794 -0.1778)
							(mid 0.249642 -0.249642)
							(end 0.1778 -0.2794)
						)
					)
					(width 0)
					(fill yes)
				)
			)
		)
		(pad "2" smd custom
			(at 0 0.4445 180)
			(size 0.1397 0.1397)
			(layers "F.Cu" "F.Mask" "F.Paste")
			(net "I2C_DRIVE_A_FLT_LED_SCL")
			(options
				(clearance outline)
				(anchor circle)
			)
			(primitives
				(gr_poly
					(pts
						(arc
							(start -0.1778 -0.2794)
							(mid -0.249642 -0.249642)
							(end -0.2794 -0.1778)
						)
						(arc
							(start -0.2794 0.1778)
							(mid -0.249642 0.249642)
							(end -0.1778 0.2794)
						)
						(arc
							(start 0.1778 0.2794)
							(mid 0.249642 0.249642)
							(end 0.2794 0.1778)
						)
						(arc
							(start 0.2794 -0.1778)
							(mid 0.249642 -0.249642)
							(end 0.1778 -0.2794)
						)
					)
					(width 0)
					(fill yes)
				)
			)
		)
	)
	(footprint ""
		(layer "F.Cu")
		(at 92.751148 -21.07438 180)
		(property "Reference" "R984"
			(at 0 0 180)
			(layer "F.SilkS")
			(hide yes)
			(effects
				(font
					(size 1.27 1.27)
				)
			)
		)
		(property "Value" "0R2J-2-GP"
			(at 0.064008 -3.993896 180)
			(unlocked yes)
			(layer "F.Fab")
			(hide yes)
			(effects
				(font
					(size 1.016 1.016)
					(thickness 0.1524)
				)
			)
		)
		(property "Device Type" "R402H16"
			(at 0.064008 -5.517896 180)
			(unlocked yes)
			(layer "F.Fab")
			(hide yes)
			(effects
				(font
					(size 1.016 1.016)
					(thickness 0.1524)
				)
			)
		)
		(duplicate_pad_numbers_are_jumpers no)
		(fp_line
			(start 0.508 -0.9398)
			(end -0.508 -0.9398)
			(stroke
				(width 0.1524)
				(type default)
			)
			(layer "F.SilkS")
		)
		(fp_line
			(start -0.508 -0.9398)
			(end -0.508 0.9398)
			(stroke
				(width 0.1524)
				(type default)
			)
			(layer "F.SilkS")
		)
		(fp_rect
			(start -0.508 0.9398)
			(end 0.508 -0.9398)
			(stroke
				(width 0)
				(type default)
			)
			(fill no)
			(layer "F.CrtYd")
		)
		(fp_rect
			(start -0.508 0.9398)
			(end 0.508 -0.9398)
			(stroke
				(width 0)
				(type default)
			)
			(fill no)
			(layer "F.Fab")
		)
		(pad "1" smd custom
			(at 0 -0.4445 180)
			(size 0.1397 0.1397)
			(layers "F.Cu" "F.Mask" "F.Paste")
			(net "GND")
			(options
				(clearance outline)
				(anchor circle)
			)
			(primitives
				(gr_poly
					(pts
						(arc
							(start -0.1778 -0.2794)
							(mid -0.249642 -0.249642)
							(end -0.2794 -0.1778)
						)
						(arc
							(start -0.2794 0.1778)
							(mid -0.249642 0.249642)
							(end -0.1778 0.2794)
						)
						(arc
							(start 0.1778 0.2794)
							(mid 0.249642 0.249642)
							(end 0.2794 0.1778)
						)
						(arc
							(start 0.2794 -0.1778)
							(mid 0.249642 -0.249642)
							(end 0.1778 -0.2794)
						)
					)
					(width 0)
					(fill yes)
				)
			)
		)
		(pad "2" smd custom
			(at 0 0.4445 180)
			(size 0.1397 0.1397)
			(layers "F.Cu" "F.Mask" "F.Paste")
			(net "IOM_A_SLOT_ID_0")
			(options
				(clearance outline)
				(anchor circle)
			)
			(primitives
				(gr_poly
					(pts
						(arc
							(start -0.1778 -0.2794)
							(mid -0.249642 -0.249642)
							(end -0.2794 -0.1778)
						)
						(arc
							(start -0.2794 0.1778)
							(mid -0.249642 0.249642)
							(end -0.1778 0.2794)
						)
						(arc
							(start 0.1778 0.2794)
							(mid 0.249642 0.249642)
							(end 0.2794 0.1778)
						)
						(arc
							(start 0.2794 -0.1778)
							(mid 0.249642 -0.249642)
							(end 0.1778 -0.2794)
						)
					)
					(width 0)
					(fill yes)
				)
			)
		)
	)
	(footprint ""
		(layer "F.Cu")
		(at 141.423898 -162.157918 180)
		(property "Reference" "R514"
			(at 0 0 180)
			(layer "F.SilkS")
			(hide yes)
			(effects
				(font
					(size 1.27 1.27)
				)
			)
		)
		(property "Value" "200KR2F-L-GP"
			(at 0.064008 -3.993896 180)
			(unlocked yes)
			(layer "F.Fab")
			(hide yes)
			(effects
				(font
					(size 1.016 1.016)
					(thickness 0.1524)
				)
			)
		)
		(property "Device Type" "R402H16"
			(at 0.064008 -5.517896 180)
			(unlocked yes)
			(layer "F.Fab")
			(hide yes)
			(effects
				(font
					(size 1.016 1.016)
					(thickness 0.1524)
				)
			)
		)
		(duplicate_pad_numbers_are_jumpers no)
		(fp_line
			(start 0.508 -0.9398)
			(end -0.508 -0.9398)
			(stroke
				(width 0.1524)
				(type default)
			)
			(layer "F.SilkS")
		)
		(fp_line
			(start -0.508 -0.9398)
			(end -0.508 0.9398)
			(stroke
				(width 0.1524)
				(type default)
			)
			(layer "F.SilkS")
		)
		(fp_rect
			(start -0.508 0.9398)
			(end 0.508 -0.9398)
			(stroke
				(width 0)
				(type default)
			)
			(fill no)
			(layer "F.CrtYd")
		)
		(fp_rect
			(start -0.508 0.9398)
			(end 0.508 -0.9398)
			(stroke
				(width 0)
				(type default)
			)
			(fill no)
			(layer "F.Fab")
		)
		(pad "1" smd custom
			(at 0 -0.4445 180)
			(size 0.1397 0.1397)
			(layers "F.Cu" "F.Mask" "F.Paste")
			(net "SW_HDD_R16")
			(options
				(clearance outline)
				(anchor circle)
			)
			(primitives
				(gr_poly
					(pts
						(arc
							(start -0.1778 -0.2794)
							(mid -0.249642 -0.249642)
							(end -0.2794 -0.1778)
						)
						(arc
							(start -0.2794 0.1778)
							(mid -0.249642 0.249642)
							(end -0.1778 0.2794)
						)
						(arc
							(start 0.1778 0.2794)
							(mid 0.249642 0.249642)
							(end 0.2794 0.1778)
						)
						(arc
							(start 0.2794 -0.1778)
							(mid 0.249642 -0.249642)
							(end 0.1778 -0.2794)
						)
					)
					(width 0)
					(fill yes)
				)
			)
		)
		(pad "2" smd custom
			(at 0 0.4445 180)
			(size 0.1397 0.1397)
			(layers "F.Cu" "F.Mask" "F.Paste")
			(net "SW_HDD_N16")
			(options
				(clearance outline)
				(anchor circle)
			)
			(primitives
				(gr_poly
					(pts
						(arc
							(start -0.1778 -0.2794)
							(mid -0.249642 -0.249642)
							(end -0.2794 -0.1778)
						)
						(arc
							(start -0.2794 0.1778)
							(mid -0.249642 0.249642)
							(end -0.1778 0.2794)
						)
						(arc
							(start 0.1778 0.2794)
							(mid 0.249642 0.249642)
							(end 0.2794 0.1778)
						)
						(arc
							(start 0.2794 -0.1778)
							(mid 0.249642 -0.249642)
							(end 0.1778 -0.2794)
						)
					)
					(width 0)
					(fill yes)
				)
			)
		)
	)
	(footprint ""
		(layer "F.Cu")
		(at 472.899994 -324.39991)
		(property "Reference" "RLED36"
			(at 0 0 0)
			(layer "F.SilkS")
			(hide yes)
			(effects
				(font
					(size 1.27 1.27)
				)
			)
		)
		(property "Value" "LED-BY-19-GP"
			(at -2.132076 1.414018 0)
			(unlocked yes)
			(layer "F.Fab")
			(hide yes)
			(effects
				(font
					(size 1.016 1.016)
					(thickness 0.1524)
				)
			)
		)
		(property "Device Type" "LED-1615-4PH26"
			(at -2.132076 -0.109982 0)
			(unlocked yes)
			(layer "F.Fab")
			(hide yes)
			(effects
				(font
					(size 1.016 1.016)
					(thickness 0.1524)
				)
			)
		)
		(duplicate_pad_numbers_are_jumpers no)
		(fp_line
			(start -1.2954 0.254)
			(end -1.2954 1.6002)
			(stroke
				(width 0.508)
				(type default)
			)
			(layer "F.SilkS")
		)
		(fp_line
			(start -1.2954 1.6002)
			(end 1.2954 1.6002)
			(stroke
				(width 0.508)
				(type default)
			)
			(layer "F.SilkS")
		)
		(fp_line
			(start -1.1176 -1.4224)
			(end 1.1176 -1.4224)
			(stroke
				(width 0.1524)
				(type default)
			)
			(layer "F.SilkS")
		)
		(fp_line
			(start -1.1176 1.4224)
			(end -1.1176 -1.4224)
			(stroke
				(width 0.1524)
				(type default)
			)
			(layer "F.SilkS")
		)
		(fp_line
			(start 1.1176 -1.4224)
			(end 1.1176 1.4224)
			(stroke
				(width 0.1524)
				(type default)
			)
			(layer "F.SilkS")
		)
		(fp_line
			(start 1.1176 1.4224)
			(end -1.1176 1.4224)
			(stroke
				(width 0.1524)
				(type default)
			)
			(layer "F.SilkS")
		)
		(fp_line
			(start 1.2954 1.6002)
			(end 1.2954 0.254)
			(stroke
				(width 0.508)
				(type default)
			)
			(layer "F.SilkS")
		)
		(fp_rect
			(start -0.7493 0.8001)
			(end 0.7493 -0.8001)
			(stroke
				(width 0)
				(type default)
			)
			(fill no)
			(layer "F.CrtYd")
		)
		(fp_poly
			(pts
				(xy -1.3716 1.6764) (xy -1.3716 -1.6764) (xy 1.3716 -1.6764) (xy 1.3716 0.0635) (xy 0.7493 0.0635)
				(xy 0.7493 -0.8001) (xy -0.7493 -0.8001) (xy -0.7493 0.8001) (xy 0.7493 0.8001) (xy 0.7493 0.0762)
				(xy 1.3716 0.0762) (xy 1.3716 1.6764)
			)
			(stroke
				(width 0)
				(type default)
			)
			(fill no)
			(layer "F.CrtYd")
		)
		(fp_rect
			(start -1.3716 1.6764)
			(end 1.3716 -1.6764)
			(stroke
				(width 0)
				(type default)
			)
			(fill no)
			(layer "F.Fab")
		)
		(pad "1" smd rect
			(at 0.50038 -0.73025)
			(size 0.7112 0.8636)
			(layers "F.Cu" "F.Mask" "F.Paste")
			(net "DRV_ACT_35")
		)
		(pad "2" smd rect
			(at -0.50038 -0.73025)
			(size 0.7112 0.8636)
			(layers "F.Cu" "F.Mask" "F.Paste")
			(net "FLT_HDD35")
		)
		(pad "3" smd rect
			(at 0.50038 0.73025)
			(size 0.7112 0.8636)
			(layers "F.Cu" "F.Mask" "F.Paste")
			(net "DRV_ACT_35_N")
		)
		(pad "4" smd rect
			(at -0.50038 0.73025)
			(size 0.7112 0.8636)
			(layers "F.Cu" "F.Mask" "F.Paste")
			(net "FLT_HDD35_N")
		)
	)
	(footprint ""
		(layer "F.Cu")
		(at 236.3724 -248.9708)
		(property "Reference" "R35"
			(at 0 0 0)
			(layer "F.SilkS")
			(hide yes)
			(effects
				(font
					(size 1.27 1.27)
				)
			)
		)
		(property "Value" "0R2J-2-GP"
			(at 0.064008 -3.993896 0)
			(unlocked yes)
			(layer "F.Fab")
			(hide yes)
			(effects
				(font
					(size 1.016 1.016)
					(thickness 0.1524)
				)
			)
		)
		(property "Device Type" "R402H16"
			(at 0.064008 -5.517896 0)
			(unlocked yes)
			(layer "F.Fab")
			(hide yes)
			(effects
				(font
					(size 1.016 1.016)
					(thickness 0.1524)
				)
			)
		)
		(duplicate_pad_numbers_are_jumpers no)
		(fp_line
			(start -0.508 -0.9398)
			(end -0.508 0.9398)
			(stroke
				(width 0.1524)
				(type default)
			)
			(layer "F.SilkS")
		)
		(fp_line
			(start 0.508 -0.9398)
			(end -0.508 -0.9398)
			(stroke
				(width 0.1524)
				(type default)
			)
			(layer "F.SilkS")
		)
		(fp_rect
			(start -0.508 0.9398)
			(end 0.508 -0.9398)
			(stroke
				(width 0)
				(type default)
			)
			(fill no)
			(layer "F.CrtYd")
		)
		(fp_rect
			(start -0.508 0.9398)
			(end 0.508 -0.9398)
			(stroke
				(width 0)
				(type default)
			)
			(fill no)
			(layer "F.Fab")
		)
		(pad "1" smd custom
			(at 0 -0.4445)
			(size 0.1397 0.1397)
			(layers "F.Cu" "F.Mask" "F.Paste")
			(net "IO_EXP4_SDA")
			(options
				(clearance outline)
				(anchor circle)
			)
			(primitives
				(gr_poly
					(pts
						(arc
							(start -0.1778 -0.2794)
							(mid -0.249642 -0.249642)
							(end -0.2794 -0.1778)
						)
						(arc
							(start -0.2794 0.1778)
							(mid -0.249642 0.249642)
							(end -0.1778 0.2794)
						)
						(arc
							(start 0.1778 0.2794)
							(mid 0.249642 0.249642)
							(end 0.2794 0.1778)
						)
						(arc
							(start 0.2794 -0.1778)
							(mid 0.249642 -0.249642)
							(end 0.1778 -0.2794)
						)
					)
					(width 0)
					(fill yes)
				)
			)
		)
		(pad "2" smd custom
			(at 0 0.4445)
			(size 0.1397 0.1397)
			(layers "F.Cu" "F.Mask" "F.Paste")
			(net "I2C_DRIVE_A_INS_SDA")
			(options
				(clearance outline)
				(anchor circle)
			)
			(primitives
				(gr_poly
					(pts
						(arc
							(start -0.1778 -0.2794)
							(mid -0.249642 -0.249642)
							(end -0.2794 -0.1778)
						)
						(arc
							(start -0.2794 0.1778)
							(mid -0.249642 0.249642)
							(end -0.1778 0.2794)
						)
						(arc
							(start 0.1778 0.2794)
							(mid 0.249642 0.249642)
							(end 0.2794 0.1778)
						)
						(arc
							(start 0.2794 -0.1778)
							(mid 0.249642 -0.249642)
							(end 0.1778 -0.2794)
						)
					)
					(width 0)
					(fill yes)
				)
			)
		)
	)
)
